(kicad_pcb
	(version 20260206)
	(generator "pcbnew")
	(generator_version "10.0")
	(general
		(thickness 1.6)
		(legacy_teardrops no)
	)
	(paper "A4")
	(title_block
		(title "baseboard — 13948-1b.1110WZS1818.brd")
		(comment 1 "Honey Badger (Wiwynn) / footprints 2047-2054 of 2523")
	)
	(layers
		(0 "F.Cu" signal "TOP")
		(4 "In1.Cu" signal "L2GND")
		(6 "In2.Cu" signal "L3")
		(8 "In3.Cu" signal "L4VCC")
		(10 "In4.Cu" signal "L5VCC")
		(12 "In5.Cu" signal "L6")
		(14 "In6.Cu" signal "L7GND")
		(2 "B.Cu" signal "BOTTOM")
		(9 "F.Adhes" user "F.Adhesive")
		(11 "B.Adhes" user "B.Adhesive")
		(13 "F.Paste" user "Package Geometry/Pastemask Top")
		(15 "B.Paste" user "Package Geometry/Pastemask Bottom")
		(5 "F.SilkS" user "Ref Des/Silkscreen Top")
		(7 "B.SilkS" user "Ref Des/Silkscreen Bottom")
		(1 "F.Mask" user "Board Geometry/Soldermask Top")
		(3 "B.Mask" user "Board Geometry/Soldermask Bottom")
		(17 "Dwgs.User" user "User.Drawings")
		(19 "Cmts.User" user "User.Comments")
		(21 "Eco1.User" user "User.Eco1")
		(23 "Eco2.User" user "User.Eco2")
		(25 "Edge.Cuts" user "Board Geometry/Outline")
		(27 "Margin" user)
		(31 "F.CrtYd" user "Package Geometry/Place Bound Top")
		(29 "B.CrtYd" user "Package Geometry/Place Bound Bottom")
		(35 "F.Fab" user "Ref Des/Assembly Top")
		(33 "B.Fab" user "Ref Des/Assembly Bottom")
	)
	(footprint ""
		(layer "B.Cu")
		(at 113.04016 -29.972 -90)
		(property "Reference" "SR645"
			(at 0 0 90)
			(layer "B.SilkS")
			(hide yes)
			(effects
				(font
					(size 1.27 1.27)
				)
				(justify mirror)
			)
		)
		(property "Value" "4K7R2F-GP"
			(at -0.064008 -3.993896 270)
			(unlocked yes)
			(layer "B.Fab")
			(hide yes)
			(effects
				(font
					(size 1.016 1.016)
					(thickness 0.1524)
				)
				(justify mirror)
			)
		)
		(property "Device Type" "R402H16"
			(at -0.064008 -5.517896 270)
			(unlocked yes)
			(layer "B.Fab")
			(hide yes)
			(effects
				(font
					(size 1.016 1.016)
					(thickness 0.1524)
				)
				(justify mirror)
			)
		)
		(duplicate_pad_numbers_are_jumpers no)
		(fp_line
			(start -0.508 -0.9398)
			(end 0.508 -0.9398)
			(stroke
				(width 0.1524)
				(type default)
			)
			(layer "B.SilkS")
		)
		(fp_line
			(start 0.508 -0.9398)
			(end 0.508 0.9398)
			(stroke
				(width 0.1524)
				(type default)
			)
			(layer "B.SilkS")
		)
		(fp_rect
			(start 0.508 0.9398)
			(end -0.508 -0.9398)
			(stroke
				(width 0)
				(type default)
			)
			(fill no)
			(layer "B.CrtYd")
		)
		(fp_rect
			(start 0.508 0.9398)
			(end -0.508 -0.9398)
			(stroke
				(width 0)
				(type default)
			)
			(fill no)
			(layer "B.Fab")
		)
		(pad "1" smd custom
			(at 0 -0.4445 90)
			(size 0.1397 0.1397)
			(layers "B.Cu" "B.Mask" "B.Paste")
			(net "P1V8_C")
			(options
				(clearance outline)
				(anchor circle)
			)
			(primitives
				(gr_poly
					(pts
						(arc
							(start -0.1778 0.2794)
							(mid -0.249642 0.249642)
							(end -0.2794 0.1778)
						)
						(arc
							(start -0.2794 -0.1778)
							(mid -0.249642 -0.249642)
							(end -0.1778 -0.2794)
						)
						(arc
							(start 0.1778 -0.2794)
							(mid 0.249642 -0.249642)
							(end 0.2794 -0.1778)
						)
						(arc
							(start 0.2794 0.1778)
							(mid 0.249642 0.249642)
							(end 0.1778 0.2794)
						)
					)
					(width 0)
					(fill yes)
				)
			)
		)
		(pad "2" smd custom
			(at 0 0.4445 90)
			(size 0.1397 0.1397)
			(layers "B.Cu" "B.Mask" "B.Paste")
			(net "IOC_UART_1_RX")
			(options
				(clearance outline)
				(anchor circle)
			)
			(primitives
				(gr_poly
					(pts
						(arc
							(start -0.1778 0.2794)
							(mid -0.249642 0.249642)
							(end -0.2794 0.1778)
						)
						(arc
							(start -0.2794 -0.1778)
							(mid -0.249642 -0.249642)
							(end -0.1778 -0.2794)
						)
						(arc
							(start 0.1778 -0.2794)
							(mid 0.249642 -0.249642)
							(end 0.2794 -0.1778)
						)
						(arc
							(start 0.2794 0.1778)
							(mid 0.249642 0.249642)
							(end 0.1778 0.2794)
						)
					)
					(width 0)
					(fill yes)
				)
			)
		)
	)
	(footprint ""
		(layer "B.Cu")
		(at 325.374 -184.404)
		(property "Reference" "R5763"
			(at 0 0 0)
			(layer "B.SilkS")
			(hide yes)
			(effects
				(font
					(size 1.27 1.27)
				)
				(justify mirror)
			)
		)
		(property "Value" "1KR2F-3-GP"
			(at -0.064008 -3.993896 0)
			(unlocked yes)
			(layer "B.Fab")
			(hide yes)
			(effects
				(font
					(size 1.016 1.016)
					(thickness 0.1524)
				)
				(justify mirror)
			)
		)
		(property "Device Type" "R402H16"
			(at -0.064008 -5.517896 0)
			(unlocked yes)
			(layer "B.Fab")
			(hide yes)
			(effects
				(font
					(size 1.016 1.016)
					(thickness 0.1524)
				)
				(justify mirror)
			)
		)
		(duplicate_pad_numbers_are_jumpers no)
		(fp_line
			(start -0.508 -0.9398)
			(end 0.508 -0.9398)
			(stroke
				(width 0.1524)
				(type default)
			)
			(layer "B.SilkS")
		)
		(fp_line
			(start 0.508 -0.9398)
			(end 0.508 0.9398)
			(stroke
				(width 0.1524)
				(type default)
			)
			(layer "B.SilkS")
		)
		(fp_rect
			(start 0.508 0.9398)
			(end -0.508 -0.9398)
			(stroke
				(width 0)
				(type default)
			)
			(fill no)
			(layer "B.CrtYd")
		)
		(fp_rect
			(start 0.508 0.9398)
			(end -0.508 -0.9398)
			(stroke
				(width 0)
				(type default)
			)
			(fill no)
			(layer "B.Fab")
		)
		(pad "1" smd custom
			(at 0 -0.4445 180)
			(size 0.1397 0.1397)
			(layers "B.Cu" "B.Mask" "B.Paste")
			(net "P0V9_E")
			(options
				(clearance outline)
				(anchor circle)
			)
			(primitives
				(gr_poly
					(pts
						(arc
							(start -0.1778 0.2794)
							(mid -0.249642 0.249642)
							(end -0.2794 0.1778)
						)
						(arc
							(start -0.2794 -0.1778)
							(mid -0.249642 -0.249642)
							(end -0.1778 -0.2794)
						)
						(arc
							(start 0.1778 -0.2794)
							(mid 0.249642 -0.249642)
							(end 0.2794 -0.1778)
						)
						(arc
							(start 0.2794 0.1778)
							(mid 0.249642 0.249642)
							(end 0.1778 0.2794)
						)
					)
					(width 0)
					(fill yes)
				)
			)
		)
		(pad "2" smd custom
			(at 0 0.4445 180)
			(size 0.1397 0.1397)
			(layers "B.Cu" "B.Mask" "B.Paste")
			(net "ADC_P0V9_E")
			(options
				(clearance outline)
				(anchor circle)
			)
			(primitives
				(gr_poly
					(pts
						(arc
							(start -0.1778 0.2794)
							(mid -0.249642 0.249642)
							(end -0.2794 0.1778)
						)
						(arc
							(start -0.2794 -0.1778)
							(mid -0.249642 -0.249642)
							(end -0.1778 -0.2794)
						)
						(arc
							(start 0.1778 -0.2794)
							(mid 0.249642 -0.249642)
							(end 0.2794 -0.1778)
						)
						(arc
							(start 0.2794 0.1778)
							(mid 0.249642 0.249642)
							(end 0.1778 0.2794)
						)
					)
					(width 0)
					(fill yes)
				)
			)
		)
	)
	(footprint ""
		(layer "B.Cu")
		(at 88.91016 -46.863)
		(property "Reference" "STP5"
			(at 0 0 0)
			(layer "B.SilkS")
			(hide yes)
			(effects
				(font
					(size 1.27 1.27)
				)
				(justify mirror)
			)
		)
		(property "Value" "TPAD28"
			(at -0.0127 -1.8034 0)
			(unlocked yes)
			(layer "B.Fab")
			(hide yes)
			(effects
				(font
					(size 1.016 1.016)
					(thickness 0.1524)
				)
				(justify mirror)
			)
		)
		(property "Device Type" "TPAD28"
			(at -0.0127 -3.3274 0)
			(unlocked yes)
			(layer "B.Fab")
			(hide yes)
			(effects
				(font
					(size 1.016 1.016)
					(thickness 0.1524)
				)
				(justify mirror)
			)
		)
		(duplicate_pad_numbers_are_jumpers no)
		(fp_poly
			(pts
				(arc
					(start 0.3556 0)
					(mid -0.3556 0)
					(end 0.3556 0)
				)
			)
			(stroke
				(width 0)
				(type default)
			)
			(fill no)
			(layer "B.CrtYd")
		)
		(fp_poly
			(pts
				(arc
					(start 0.6096 0)
					(mid -0.6096 0)
					(end 0.6096 0)
				)
			)
			(stroke
				(width 0)
				(type default)
			)
			(fill no)
			(layer "B.Fab")
		)
		(pad "1" smd circle
			(at 0 0 180)
			(size 0.7112 0.7112)
			(layers "B.Cu" "B.Mask" "B.Paste")
			(net "SIO_DIN_0")
		)
	)
	(footprint ""
		(layer "B.Cu")
		(at 98.679 -50.0888 -90)
		(property "Reference" "SC1040"
			(at 0 0 90)
			(layer "B.SilkS")
			(hide yes)
			(effects
				(font
					(size 1.27 1.27)
				)
				(justify mirror)
			)
		)
		(property "Value" "SCD1U16V2KX-3GP"
			(at -1.1811 -2.7051 270)
			(unlocked yes)
			(layer "B.Fab")
			(hide yes)
			(effects
				(font
					(size 1.016 1.016)
					(thickness 0.1524)
				)
				(justify mirror)
			)
		)
		(property "Device Type" "C402H22"
			(at -1.1811 -4.2291 270)
			(unlocked yes)
			(layer "B.Fab")
			(hide yes)
			(effects
				(font
					(size 1.016 1.016)
					(thickness 0.1524)
				)
				(justify mirror)
			)
		)
		(duplicate_pad_numbers_are_jumpers no)
		(fp_rect
			(start 0.4318 0.9525)
			(end -0.4318 -0.9525)
			(stroke
				(width 0)
				(type default)
			)
			(fill no)
			(layer "B.CrtYd")
		)
		(fp_rect
			(start 0.4318 0.9525)
			(end -0.4318 -0.9525)
			(stroke
				(width 0)
				(type default)
			)
			(fill no)
			(layer "B.Fab")
		)
		(pad "1" smd custom
			(at 0 -0.4445 90)
			(size 0.1524 0.1524)
			(layers "B.Cu" "B.Mask" "B.Paste")
			(net "P0V955_C")
			(options
				(clearance outline)
				(anchor circle)
			)
			(primitives
				(gr_poly
					(pts
						(arc
							(start 0.3048 0.2032)
							(mid 0.275042 0.275042)
							(end 0.2032 0.3048)
						)
						(arc
							(start -0.2032 0.3048)
							(mid -0.275042 0.275042)
							(end -0.3048 0.2032)
						)
						(arc
							(start -0.3048 -0.2032)
							(mid -0.275042 -0.275042)
							(end -0.2032 -0.3048)
						)
						(arc
							(start 0.2032 -0.3048)
							(mid 0.275042 -0.275042)
							(end 0.3048 -0.2032)
						)
					)
					(width 0)
					(fill yes)
				)
			)
		)
		(pad "2" smd custom
			(at 0 0.4445 90)
			(size 0.1524 0.1524)
			(layers "B.Cu" "B.Mask" "B.Paste")
			(net "GND")
			(options
				(clearance outline)
				(anchor circle)
			)
			(primitives
				(gr_poly
					(pts
						(arc
							(start 0.3048 0.2032)
							(mid 0.275042 0.275042)
							(end 0.2032 0.3048)
						)
						(arc
							(start -0.2032 0.3048)
							(mid -0.275042 0.275042)
							(end -0.3048 0.2032)
						)
						(arc
							(start -0.3048 -0.2032)
							(mid -0.275042 -0.275042)
							(end -0.2032 -0.3048)
						)
						(arc
							(start 0.2032 -0.3048)
							(mid 0.275042 -0.275042)
							(end 0.3048 -0.2032)
						)
					)
					(width 0)
					(fill yes)
				)
			)
		)
	)
	(footprint ""
		(layer "B.Cu")
		(at 108.008166 -32.6898)
		(property "Reference" "STP44"
			(at 0 0 0)
			(layer "B.SilkS")
			(hide yes)
			(effects
				(font
					(size 1.27 1.27)
				)
				(justify mirror)
			)
		)
		(property "Value" "TPAD28"
			(at -0.0127 -1.8034 0)
			(unlocked yes)
			(layer "B.Fab")
			(hide yes)
			(effects
				(font
					(size 1.016 1.016)
					(thickness 0.1524)
				)
				(justify mirror)
			)
		)
		(property "Device Type" "TPAD28"
			(at -0.0127 -3.3274 0)
			(unlocked yes)
			(layer "B.Fab")
			(hide yes)
			(effects
				(font
					(size 1.016 1.016)
					(thickness 0.1524)
				)
				(justify mirror)
			)
		)
		(duplicate_pad_numbers_are_jumpers no)
		(fp_poly
			(pts
				(arc
					(start 0.3556 0)
					(mid -0.3556 0)
					(end 0.3556 0)
				)
			)
			(stroke
				(width 0)
				(type default)
			)
			(fill no)
			(layer "B.CrtYd")
		)
		(fp_poly
			(pts
				(arc
					(start 0.6096 0)
					(mid -0.6096 0)
					(end 0.6096 0)
				)
			)
			(stroke
				(width 0)
				(type default)
			)
			(fill no)
			(layer "B.Fab")
		)
		(pad "1" smd circle
			(at 0 0 180)
			(size 0.7112 0.7112)
			(layers "B.Cu" "B.Mask" "B.Paste")
			(net "IOC_GPIO_3")
		)
	)
	(footprint ""
		(layer "B.Cu")
		(at 111.41837 -95.1738 -90)
		(property "Reference" "SC1249"
			(at 0 0 90)
			(layer "B.SilkS")
			(hide yes)
			(effects
				(font
					(size 1.27 1.27)
				)
				(justify mirror)
			)
		)
		(property "Value" "SCD1U6D3V1KX-GP"
			(at 2.8321 -1.7399 270)
			(unlocked yes)
			(layer "B.Fab")
			(hide yes)
			(effects
				(font
					(size 1.016 1.016)
					(thickness 0.1524)
				)
				(justify mirror)
			)
		)
		(property "Device Type" "C0201H13"
			(at 2.8321 -3.2639 270)
			(unlocked yes)
			(layer "B.Fab")
			(hide yes)
			(effects
				(font
					(size 1.016 1.016)
					(thickness 0.1524)
				)
				(justify mirror)
			)
		)
		(duplicate_pad_numbers_are_jumpers no)
		(fp_rect
			(start 0.2794 0.6477)
			(end -0.2794 -0.6477)
			(stroke
				(width 0)
				(type default)
			)
			(fill no)
			(layer "B.CrtYd")
		)
		(fp_rect
			(start 0.2794 0.6477)
			(end -0.2794 -0.6477)
			(stroke
				(width 0)
				(type default)
			)
			(fill no)
			(layer "B.Fab")
		)
		(pad "1" smd custom
			(at 0 -0.2794 90)
			(size 0.0762 0.0762)
			(layers "B.Cu" "B.Mask" "B.Paste")
			(net "P0V9_E")
			(options
				(clearance outline)
				(anchor circle)
			)
			(primitives
				(gr_poly
					(pts
						(arc
							(start 0.1524 0.127)
							(mid 0.137521 0.162921)
							(end 0.1016 0.1778)
						)
						(arc
							(start -0.1016 0.1778)
							(mid -0.137521 0.162921)
							(end -0.1524 0.127)
						)
						(arc
							(start -0.1524 -0.127)
							(mid -0.137521 -0.162921)
							(end -0.1016 -0.1778)
						)
						(arc
							(start 0.1016 -0.1778)
							(mid 0.137521 -0.162921)
							(end 0.1524 -0.127)
						)
					)
					(width 0)
					(fill yes)
				)
			)
		)
		(pad "2" smd custom
			(at 0 0.2794 90)
			(size 0.0762 0.0762)
			(layers "B.Cu" "B.Mask" "B.Paste")
			(net "GND")
			(options
				(clearance outline)
				(anchor circle)
			)
			(primitives
				(gr_poly
					(pts
						(arc
							(start 0.1524 0.127)
							(mid 0.137521 0.162921)
							(end 0.1016 0.1778)
						)
						(arc
							(start -0.1016 0.1778)
							(mid -0.137521 0.162921)
							(end -0.1524 0.127)
						)
						(arc
							(start -0.1524 -0.127)
							(mid -0.137521 -0.162921)
							(end -0.1016 -0.1778)
						)
						(arc
							(start 0.1016 -0.1778)
							(mid 0.137521 -0.162921)
							(end 0.1524 -0.127)
						)
					)
					(width 0)
					(fill yes)
				)
			)
		)
	)
	(footprint ""
		(layer "B.Cu")
		(at 114.472212 -205.867)
		(property "Reference" "SC1290"
			(at 0 0 0)
			(layer "B.SilkS")
			(hide yes)
			(effects
				(font
					(size 1.27 1.27)
				)
				(justify mirror)
			)
		)
		(property "Value" "SCD1U16V2KX-3GP"
			(at -1.1811 -2.7051 0)
			(unlocked yes)
			(layer "B.Fab")
			(hide yes)
			(effects
				(font
					(size 1.016 1.016)
					(thickness 0.1524)
				)
				(justify mirror)
			)
		)
		(property "Device Type" "C402H22"
			(at -1.1811 -4.2291 0)
			(unlocked yes)
			(layer "B.Fab")
			(hide yes)
			(effects
				(font
					(size 1.016 1.016)
					(thickness 0.1524)
				)
				(justify mirror)
			)
		)
		(duplicate_pad_numbers_are_jumpers no)
		(fp_rect
			(start 0.4318 0.9525)
			(end -0.4318 -0.9525)
			(stroke
				(width 0)
				(type default)
			)
			(fill no)
			(layer "B.CrtYd")
		)
		(fp_rect
			(start 0.4318 0.9525)
			(end -0.4318 -0.9525)
			(stroke
				(width 0)
				(type default)
			)
			(fill no)
			(layer "B.Fab")
		)
		(pad "1" smd custom
			(at 0 -0.4445 180)
			(size 0.1524 0.1524)
			(layers "B.Cu" "B.Mask" "B.Paste")
			(net "1.2V_REDV")
			(options
				(clearance outline)
				(anchor circle)
			)
			(primitives
				(gr_poly
					(pts
						(arc
							(start 0.3048 0.2032)
							(mid 0.275042 0.275042)
							(end 0.2032 0.3048)
						)
						(arc
							(start -0.2032 0.3048)
							(mid -0.275042 0.275042)
							(end -0.3048 0.2032)
						)
						(arc
							(start -0.3048 -0.2032)
							(mid -0.275042 -0.275042)
							(end -0.2032 -0.3048)
						)
						(arc
							(start 0.2032 -0.3048)
							(mid 0.275042 -0.275042)
							(end 0.3048 -0.2032)
						)
					)
					(width 0)
					(fill yes)
				)
			)
		)
		(pad "2" smd custom
			(at 0 0.4445 180)
			(size 0.1524 0.1524)
			(layers "B.Cu" "B.Mask" "B.Paste")
			(net "GND")
			(options
				(clearance outline)
				(anchor circle)
			)
			(primitives
				(gr_poly
					(pts
						(arc
							(start 0.3048 0.2032)
							(mid 0.275042 0.275042)
							(end 0.2032 0.3048)
						)
						(arc
							(start -0.2032 0.3048)
							(mid -0.275042 0.275042)
							(end -0.3048 0.2032)
						)
						(arc
							(start -0.3048 -0.2032)
							(mid -0.275042 -0.275042)
							(end -0.2032 -0.3048)
						)
						(arc
							(start 0.2032 -0.3048)
							(mid 0.275042 -0.275042)
							(end 0.3048 -0.2032)
						)
					)
					(width 0)
					(fill yes)
				)
			)
		)
	)
	(footprint ""
		(layer "B.Cu")
		(at 12.058904 -100.400866)
		(property "Reference" "C130"
			(at 0 0 0)
			(layer "B.SilkS")
			(hide yes)
			(effects
				(font
					(size 1.27 1.27)
				)
				(justify mirror)
			)
		)
		(property "Value" "SCD01U50V2KX-1GP"
			(at -1.1811 -2.7051 0)
			(unlocked yes)
			(layer "B.Fab")
			(hide yes)
			(effects
				(font
					(size 1.016 1.016)
					(thickness 0.1524)
				)
				(justify mirror)
			)
		)
		(property "Device Type" "C402H22"
			(at -1.1811 -4.2291 0)
			(unlocked yes)
			(layer "B.Fab")
			(hide yes)
			(effects
				(font
					(size 1.016 1.016)
					(thickness 0.1524)
				)
				(justify mirror)
			)
		)
		(duplicate_pad_numbers_are_jumpers no)
		(fp_rect
			(start 0.4318 0.9525)
			(end -0.4318 -0.9525)
			(stroke
				(width 0)
				(type default)
			)
			(fill no)
			(layer "B.CrtYd")
		)
		(fp_rect
			(start 0.4318 0.9525)
			(end -0.4318 -0.9525)
			(stroke
				(width 0)
				(type default)
			)
			(fill no)
			(layer "B.Fab")
		)
		(pad "1" smd custom
			(at 0 -0.4445 180)
			(size 0.1524 0.1524)
			(layers "B.Cu" "B.Mask" "B.Paste")
			(net "IOC_SAS_RX_N4")
			(options
				(clearance outline)
				(anchor circle)
			)
			(primitives
				(gr_poly
					(pts
						(arc
							(start 0.3048 0.2032)
							(mid 0.275042 0.275042)
							(end 0.2032 0.3048)
						)
						(arc
							(start -0.2032 0.3048)
							(mid -0.275042 0.275042)
							(end -0.3048 0.2032)
						)
						(arc
							(start -0.3048 -0.2032)
							(mid -0.275042 -0.275042)
							(end -0.2032 -0.3048)
						)
						(arc
							(start 0.2032 -0.3048)
							(mid 0.275042 -0.275042)
							(end 0.3048 -0.2032)
						)
					)
					(width 0)
					(fill yes)
				)
			)
		)
		(pad "2" smd custom
			(at 0 0.4445 180)
			(size 0.1524 0.1524)
			(layers "B.Cu" "B.Mask" "B.Paste")
			(net "SAS_EXT_CONN_RX16_N")
			(options
				(clearance outline)
				(anchor circle)
			)
			(primitives
				(gr_poly
					(pts
						(arc
							(start 0.3048 0.2032)
							(mid 0.275042 0.275042)
							(end 0.2032 0.3048)
						)
						(arc
							(start -0.2032 0.3048)
							(mid -0.275042 0.275042)
							(end -0.3048 0.2032)
						)
						(arc
							(start -0.3048 -0.2032)
							(mid -0.275042 -0.275042)
							(end -0.2032 -0.3048)
						)
						(arc
							(start 0.2032 -0.3048)
							(mid 0.275042 -0.275042)
							(end 0.3048 -0.2032)
						)
					)
					(width 0)
					(fill yes)
				)
			)
		)
	)
)
